(kicad_pcb
	(version 20260206)
	(generator "pcbnew")
	(generator_version "10.0")
	(general
		(thickness 1.6)
		(legacy_teardrops no)
	)
	(paper "A4")
	(title_block
		(title "v1-chassis-manager — T6M_CM_d_v01_1031_1645.brd")
		(comment 1 "Open CloudServer (Microsoft) / footprints 1262-1270 of 2512")
	)
	(layers
		(0 "F.Cu" signal "TOP")
		(4 "In1.Cu" signal "GND1")
		(6 "In2.Cu" signal "IN1")
		(8 "In3.Cu" signal "VCC1")
		(10 "In4.Cu" signal "VCC2")
		(12 "In5.Cu" signal "GND2")
		(14 "In6.Cu" signal "IN2")
		(16 "In7.Cu" signal "IN3")
		(18 "In8.Cu" signal "GND3")
		(2 "B.Cu" signal "BOTTOM")
		(9 "F.Adhes" user "F.Adhesive")
		(11 "B.Adhes" user "B.Adhesive")
		(13 "F.Paste" user "Package Geometry/Pastemask Top")
		(15 "B.Paste" user "Package Geometry/Pastemask Bottom")
		(5 "F.SilkS" user "Ref Des/Silkscreen Top")
		(7 "B.SilkS" user "Ref Des/Silkscreen Bottom")
		(1 "F.Mask" user "Board Geometry/Soldermask Top")
		(3 "B.Mask" user "Board Geometry/Soldermask Bottom")
		(17 "Dwgs.User" user "User.Drawings")
		(19 "Cmts.User" user "User.Comments")
		(21 "Eco1.User" user "User.Eco1")
		(23 "Eco2.User" user "User.Eco2")
		(25 "Edge.Cuts" user "Board Geometry/Outline")
		(27 "Margin" user)
		(31 "F.CrtYd" user "Package Geometry/Place Bound Top")
		(29 "B.CrtYd" user "Package Geometry/Place Bound Bottom")
		(35 "F.Fab" user "Ref Des/Assembly Top")
		(33 "B.Fab" user "Ref Des/Assembly Bottom")
	)
	(footprint ""
		(layer "F.Cu")
		(at 162.696906 -116.303552)
		(property "Reference" "R175"
			(at -4.639564 0.997204 0)
			(unlocked yes)
			(layer "F.SilkS")
			(effects
				(font
					(size 0.7874 0.5842)
					(thickness 0.1524)
				)
				(justify left)
			)
		)
		(property "Value" ""
			(at 0 0 0)
			(layer "F.Fab")
			(effects
				(font
					(size 1.27 1.27)
				)
			)
		)
		(duplicate_pad_numbers_are_jumpers no)
		(fp_line
			(start -0.7874 -0.4064)
			(end 0.7874 -0.4064)
			(stroke
				(width 0.1524)
				(type default)
			)
			(layer "F.SilkS")
		)
		(fp_line
			(start -0.7874 0.4064)
			(end -0.7874 -0.4064)
			(stroke
				(width 0.1524)
				(type default)
			)
			(layer "F.SilkS")
		)
		(fp_line
			(start 0.7874 -0.4064)
			(end 0.7874 0.4064)
			(stroke
				(width 0.1524)
				(type default)
			)
			(layer "F.SilkS")
		)
		(fp_line
			(start 0.7874 0.4064)
			(end -0.7874 0.4064)
			(stroke
				(width 0.1524)
				(type default)
			)
			(layer "F.SilkS")
		)
		(fp_poly
			(pts
				(xy -0.508 0.2794) (xy -0.508 0.2286) (xy -0.635 0.2286) (xy -0.635 -0.254) (xy -0.5334 -0.254)
				(xy -0.5334 -0.2794) (xy 0.5334 -0.2794) (xy 0.5334 -0.254) (xy 0.635 -0.254) (xy 0.635 0.254) (xy 0.5334 0.254)
				(xy 0.5334 0.2794)
			)
			(stroke
				(width 0)
				(type default)
			)
			(fill no)
			(layer "F.CrtYd")
		)
		(pad "1" smd rect
			(at 0.40005 0)
			(size 0.4572 0.508)
			(layers "F.Cu" "F.Mask" "F.Paste")
			(net "RST_CPU_NODE1_SRTCRST_L")
		)
		(pad "2" smd rect
			(at -0.40005 0)
			(size 0.4572 0.508)
			(layers "F.Cu" "F.Mask" "F.Paste")
			(net "P3V3_RTC_NODE1")
		)
	)
	(footprint ""
		(layer "F.Cu")
		(at 179.364894 -130.36042 180)
		(property "Reference" "R1041"
			(at -9.945624 -0.306832 0)
			(unlocked yes)
			(layer "F.SilkS")
			(effects
				(font
					(size 0.7874 0.5842)
					(thickness 0.1524)
				)
				(justify left)
			)
		)
		(property "Value" ""
			(at 0 0 180)
			(layer "F.Fab")
			(effects
				(font
					(size 1.27 1.27)
				)
			)
		)
		(duplicate_pad_numbers_are_jumpers no)
		(fp_line
			(start 0.7874 0.4064)
			(end -0.7874 0.4064)
			(stroke
				(width 0.1524)
				(type default)
			)
			(layer "F.SilkS")
		)
		(fp_line
			(start 0.7874 -0.4064)
			(end 0.7874 0.4064)
			(stroke
				(width 0.1524)
				(type default)
			)
			(layer "F.SilkS")
		)
		(fp_line
			(start -0.7874 0.4064)
			(end -0.7874 -0.4064)
			(stroke
				(width 0.1524)
				(type default)
			)
			(layer "F.SilkS")
		)
		(fp_line
			(start -0.7874 -0.4064)
			(end 0.7874 -0.4064)
			(stroke
				(width 0.1524)
				(type default)
			)
			(layer "F.SilkS")
		)
		(fp_poly
			(pts
				(xy -0.508 0.2794) (xy -0.508 0.2286) (xy -0.635 0.2286) (xy -0.635 -0.254) (xy -0.5334 -0.254)
				(xy -0.5334 -0.2794) (xy 0.5334 -0.2794) (xy 0.5334 -0.254) (xy 0.635 -0.254) (xy 0.635 0.254) (xy 0.5334 0.254)
				(xy 0.5334 0.2794)
			)
			(stroke
				(width 0)
				(type default)
			)
			(fill no)
			(layer "F.CrtYd")
		)
		(pad "1" smd rect
			(at 0.40005 0 180)
			(size 0.4572 0.508)
			(layers "F.Cu" "F.Mask" "F.Paste")
			(net "FM_CPLD_NODE1_WDT")
		)
		(pad "2" smd rect
			(at -0.40005 0 180)
			(size 0.4572 0.508)
			(layers "F.Cu" "F.Mask" "F.Paste")
			(net "P3V3_STB_NODE1")
		)
	)
	(footprint ""
		(layer "F.Cu")
		(at 133.33857 -26.569416 -90)
		(property "Reference" "R1147"
			(at 5.325618 -0.231648 90)
			(unlocked yes)
			(layer "F.SilkS")
			(effects
				(font
					(size 0.7874 0.5842)
					(thickness 0.1524)
				)
				(justify left)
			)
		)
		(property "Value" ""
			(at 0 0 270)
			(layer "F.Fab")
			(effects
				(font
					(size 1.27 1.27)
				)
			)
		)
		(duplicate_pad_numbers_are_jumpers no)
		(fp_line
			(start -0.7874 0.4064)
			(end -0.7874 -0.4064)
			(stroke
				(width 0.1524)
				(type default)
			)
			(layer "F.SilkS")
		)
		(fp_line
			(start 0.7874 0.4064)
			(end -0.7874 0.4064)
			(stroke
				(width 0.1524)
				(type default)
			)
			(layer "F.SilkS")
		)
		(fp_line
			(start -0.7874 -0.4064)
			(end 0.7874 -0.4064)
			(stroke
				(width 0.1524)
				(type default)
			)
			(layer "F.SilkS")
		)
		(fp_line
			(start 0.7874 -0.4064)
			(end 0.7874 0.4064)
			(stroke
				(width 0.1524)
				(type default)
			)
			(layer "F.SilkS")
		)
		(fp_poly
			(pts
				(xy -0.508 0.2794) (xy -0.508 0.2286) (xy -0.635 0.2286) (xy -0.635 -0.254) (xy -0.5334 -0.254)
				(xy -0.5334 -0.2794) (xy 0.5334 -0.2794) (xy 0.5334 -0.254) (xy 0.635 -0.254) (xy 0.635 0.254) (xy 0.5334 0.254)
				(xy 0.5334 0.2794)
			)
			(stroke
				(width 0)
				(type default)
			)
			(fill no)
			(layer "F.CrtYd")
		)
		(pad "1" smd rect
			(at 0.40005 0 270)
			(size 0.4572 0.508)
			(layers "F.Cu" "F.Mask" "F.Paste")
			(net "P3V3_STB_NODE1")
		)
		(pad "2" smd rect
			(at -0.40005 0 270)
			(size 0.4572 0.508)
			(layers "F.Cu" "F.Mask" "F.Paste")
			(net "SIO_PIN82")
		)
	)
	(footprint ""
		(layer "F.Cu")
		(at 53.76164 -99.105212 -90)
		(property "Reference" "C137"
			(at 0.63373 -1.409954 90)
			(unlocked yes)
			(layer "F.SilkS")
			(effects
				(font
					(size 0.7874 0.5842)
					(thickness 0.1524)
				)
				(justify left)
			)
		)
		(property "Value" ""
			(at 0 0 270)
			(layer "F.Fab")
			(effects
				(font
					(size 1.27 1.27)
				)
			)
		)
		(duplicate_pad_numbers_are_jumpers no)
		(fp_line
			(start -0.7874 0.4064)
			(end -0.7874 -0.4064)
			(stroke
				(width 0.1524)
				(type default)
			)
			(layer "F.SilkS")
		)
		(fp_line
			(start 0.7874 0.4064)
			(end -0.7874 0.4064)
			(stroke
				(width 0.1524)
				(type default)
			)
			(layer "F.SilkS")
		)
		(fp_line
			(start 0 0.381)
			(end 0 -0.381)
			(stroke
				(width 0.1524)
				(type default)
			)
			(layer "F.SilkS")
		)
		(fp_line
			(start -0.7874 -0.4064)
			(end 0.7874 -0.4064)
			(stroke
				(width 0.1524)
				(type default)
			)
			(layer "F.SilkS")
		)
		(fp_line
			(start 0.7874 -0.4064)
			(end 0.7874 0.4064)
			(stroke
				(width 0.1524)
				(type default)
			)
			(layer "F.SilkS")
		)
		(fp_poly
			(pts
				(xy -0.5334 0.254) (xy -0.635 0.254) (xy -0.635 0.2286) (xy -0.635 -0.254) (xy -0.5334 -0.254) (xy -0.5334 -0.2794)
				(xy 0.5334 -0.2794) (xy 0.5334 -0.254) (xy 0.635 -0.254) (xy 0.635 0.254) (xy 0.5334 0.254) (xy 0.5334 0.2794)
				(xy -0.508 0.2794) (xy -0.5334 0.2794)
			)
			(stroke
				(width 0)
				(type default)
			)
			(fill no)
			(layer "F.CrtYd")
		)
		(pad "1" smd rect
			(at 0.40005 0 270)
			(size 0.4572 0.508)
			(layers "F.Cu" "F.Mask" "F.Paste")
			(net "A_CPU0_NODE1_THERMDA")
		)
		(pad "2" smd rect
			(at -0.40005 0 270)
			(size 0.4572 0.508)
			(layers "F.Cu" "F.Mask" "F.Paste")
			(net "A_CPU0_NODE1_THERMDC")
		)
	)
	(footprint ""
		(layer "F.Cu")
		(at 168.258744 -93.866208)
		(property "Reference" "C366"
			(at 5.086096 0.54991 90)
			(unlocked yes)
			(layer "F.SilkS")
			(effects
				(font
					(size 0.7874 0.5842)
					(thickness 0.1524)
				)
				(justify left)
			)
		)
		(property "Value" ""
			(at 0 0 0)
			(layer "F.Fab")
			(effects
				(font
					(size 1.27 1.27)
				)
			)
		)
		(duplicate_pad_numbers_are_jumpers no)
		(fp_line
			(start -0.7874 -0.4064)
			(end 0.7874 -0.4064)
			(stroke
				(width 0.1524)
				(type default)
			)
			(layer "F.SilkS")
		)
		(fp_line
			(start -0.7874 0.4064)
			(end -0.7874 -0.4064)
			(stroke
				(width 0.1524)
				(type default)
			)
			(layer "F.SilkS")
		)
		(fp_line
			(start 0 0.381)
			(end 0 -0.381)
			(stroke
				(width 0.1524)
				(type default)
			)
			(layer "F.SilkS")
		)
		(fp_line
			(start 0.7874 -0.4064)
			(end 0.7874 0.4064)
			(stroke
				(width 0.1524)
				(type default)
			)
			(layer "F.SilkS")
		)
		(fp_line
			(start 0.7874 0.4064)
			(end -0.7874 0.4064)
			(stroke
				(width 0.1524)
				(type default)
			)
			(layer "F.SilkS")
		)
		(fp_poly
			(pts
				(xy -0.5334 0.254) (xy -0.635 0.254) (xy -0.635 0.2286) (xy -0.635 -0.254) (xy -0.5334 -0.254) (xy -0.5334 -0.2794)
				(xy 0.5334 -0.2794) (xy 0.5334 -0.254) (xy 0.635 -0.254) (xy 0.635 0.254) (xy 0.5334 0.254) (xy 0.5334 0.2794)
				(xy -0.508 0.2794) (xy -0.5334 0.2794)
			)
			(stroke
				(width 0)
				(type default)
			)
			(fill no)
			(layer "F.CrtYd")
		)
		(pad "1" smd rect
			(at 0.40005 0)
			(size 0.4572 0.508)
			(layers "F.Cu" "F.Mask" "F.Paste")
			(net "USB_NODE1_XTA2")
		)
		(pad "2" smd rect
			(at -0.40005 0)
			(size 0.4572 0.508)
			(layers "F.Cu" "F.Mask" "F.Paste")
			(net "GND")
		)
	)
	(footprint ""
		(layer "F.Cu")
		(at 137.52576 -181.506622 -90)
		(property "Reference" "C903"
			(at 0.169926 1.011174 90)
			(unlocked yes)
			(layer "F.SilkS")
			(effects
				(font
					(size 0.7874 0.5842)
					(thickness 0.1524)
				)
				(justify left)
			)
		)
		(property "Value" ""
			(at 0 0 270)
			(layer "F.Fab")
			(effects
				(font
					(size 1.27 1.27)
				)
			)
		)
		(duplicate_pad_numbers_are_jumpers no)
		(fp_line
			(start -0.7874 0.4064)
			(end -0.7874 -0.4064)
			(stroke
				(width 0.1524)
				(type default)
			)
			(layer "F.SilkS")
		)
		(fp_line
			(start 0.7874 0.4064)
			(end -0.7874 0.4064)
			(stroke
				(width 0.1524)
				(type default)
			)
			(layer "F.SilkS")
		)
		(fp_line
			(start 0 0.381)
			(end 0 -0.381)
			(stroke
				(width 0.1524)
				(type default)
			)
			(layer "F.SilkS")
		)
		(fp_line
			(start -0.7874 -0.4064)
			(end 0.7874 -0.4064)
			(stroke
				(width 0.1524)
				(type default)
			)
			(layer "F.SilkS")
		)
		(fp_line
			(start 0.7874 -0.4064)
			(end 0.7874 0.4064)
			(stroke
				(width 0.1524)
				(type default)
			)
			(layer "F.SilkS")
		)
		(fp_poly
			(pts
				(xy -0.5334 0.254) (xy -0.635 0.254) (xy -0.635 0.2286) (xy -0.635 -0.254) (xy -0.5334 -0.254) (xy -0.5334 -0.2794)
				(xy 0.5334 -0.2794) (xy 0.5334 -0.254) (xy 0.635 -0.254) (xy 0.635 0.254) (xy 0.5334 0.254) (xy 0.5334 0.2794)
				(xy -0.508 0.2794) (xy -0.5334 0.2794)
			)
			(stroke
				(width 0)
				(type default)
			)
			(fill no)
			(layer "F.CrtYd")
		)
		(pad "1" smd rect
			(at 0.40005 0 270)
			(size 0.4572 0.508)
			(layers "F.Cu" "F.Mask" "F.Paste")
			(net "P3V3_NODE1")
		)
		(pad "2" smd rect
			(at -0.40005 0 270)
			(size 0.4572 0.508)
			(layers "F.Cu" "F.Mask" "F.Paste")
			(net "GND")
		)
	)
	(footprint ""
		(layer "F.Cu")
		(at 15.997174 -16.260572 90)
		(property "Reference" "C543"
			(at -1.500124 -6.16966 90)
			(unlocked yes)
			(layer "F.SilkS")
			(effects
				(font
					(size 0.7874 0.5842)
					(thickness 0.1524)
				)
				(justify left)
			)
		)
		(property "Value" ""
			(at 0 0 90)
			(layer "F.Fab")
			(effects
				(font
					(size 1.27 1.27)
				)
			)
		)
		(duplicate_pad_numbers_are_jumpers no)
		(fp_line
			(start 0.7874 -0.4064)
			(end 0.7874 0.4064)
			(stroke
				(width 0.1524)
				(type default)
			)
			(layer "F.SilkS")
		)
		(fp_line
			(start -0.7874 -0.4064)
			(end 0.7874 -0.4064)
			(stroke
				(width 0.1524)
				(type default)
			)
			(layer "F.SilkS")
		)
		(fp_line
			(start 0 0.381)
			(end 0 -0.381)
			(stroke
				(width 0.1524)
				(type default)
			)
			(layer "F.SilkS")
		)
		(fp_line
			(start 0.7874 0.4064)
			(end -0.7874 0.4064)
			(stroke
				(width 0.1524)
				(type default)
			)
			(layer "F.SilkS")
		)
		(fp_line
			(start -0.7874 0.4064)
			(end -0.7874 -0.4064)
			(stroke
				(width 0.1524)
				(type default)
			)
			(layer "F.SilkS")
		)
		(fp_poly
			(pts
				(xy -0.5334 0.254) (xy -0.635 0.254) (xy -0.635 0.2286) (xy -0.635 -0.254) (xy -0.5334 -0.254) (xy -0.5334 -0.2794)
				(xy 0.5334 -0.2794) (xy 0.5334 -0.254) (xy 0.635 -0.254) (xy 0.635 0.254) (xy 0.5334 0.254) (xy 0.5334 0.2794)
				(xy -0.508 0.2794) (xy -0.5334 0.2794)
			)
			(stroke
				(width 0)
				(type default)
			)
			(fill no)
			(layer "F.CrtYd")
		)
		(pad "1" smd rect
			(at 0.40005 0 90)
			(size 0.4572 0.508)
			(layers "F.Cu" "F.Mask" "F.Paste")
			(net "P3V3_NODE1")
		)
		(pad "2" smd rect
			(at -0.40005 0 90)
			(size 0.4572 0.508)
			(layers "F.Cu" "F.Mask" "F.Paste")
			(net "GND")
		)
	)
	(footprint ""
		(layer "F.Cu")
		(at 38.699948 -3.086354 180)
		(property "Reference" "R1241"
			(at 15.15618 -1.703578 0)
			(unlocked yes)
			(layer "F.SilkS")
			(effects
				(font
					(size 0.7874 0.5842)
					(thickness 0.1524)
				)
				(justify left)
			)
		)
		(property "Value" ""
			(at 0 0 180)
			(layer "F.Fab")
			(effects
				(font
					(size 1.27 1.27)
				)
			)
		)
		(duplicate_pad_numbers_are_jumpers no)
		(fp_line
			(start 0.7874 0.4064)
			(end -0.7874 0.4064)
			(stroke
				(width 0.1524)
				(type default)
			)
			(layer "F.SilkS")
		)
		(fp_line
			(start 0.7874 -0.4064)
			(end 0.7874 0.4064)
			(stroke
				(width 0.1524)
				(type default)
			)
			(layer "F.SilkS")
		)
		(fp_line
			(start -0.7874 0.4064)
			(end -0.7874 -0.4064)
			(stroke
				(width 0.1524)
				(type default)
			)
			(layer "F.SilkS")
		)
		(fp_line
			(start -0.7874 -0.4064)
			(end 0.7874 -0.4064)
			(stroke
				(width 0.1524)
				(type default)
			)
			(layer "F.SilkS")
		)
		(fp_poly
			(pts
				(xy -0.508 0.2794) (xy -0.508 0.2286) (xy -0.635 0.2286) (xy -0.635 -0.254) (xy -0.5334 -0.254)
				(xy -0.5334 -0.2794) (xy 0.5334 -0.2794) (xy 0.5334 -0.254) (xy 0.635 -0.254) (xy 0.635 0.254) (xy 0.5334 0.254)
				(xy 0.5334 0.2794)
			)
			(stroke
				(width 0)
				(type default)
			)
			(fill no)
			(layer "F.CrtYd")
		)
		(pad "1" smd rect
			(at 0.40005 0 180)
			(size 0.4572 0.508)
			(layers "F.Cu" "F.Mask" "F.Paste")
			(net "GND")
		)
		(pad "2" smd rect
			(at -0.40005 0 180)
			(size 0.4572 0.508)
			(layers "F.Cu" "F.Mask" "F.Paste")
			(net "FM_CPLD_NODE1_PVDDR_STB_EN")
		)
	)
	(footprint ""
		(layer "F.Cu")
		(at 94.211394 -184.774586)
		(property "Reference" "C690"
			(at -1.182878 -7.195566 0)
			(unlocked yes)
			(layer "F.SilkS")
			(effects
				(font
					(size 0.7874 0.5842)
					(thickness 0.1524)
				)
				(justify left)
			)
		)
		(property "Value" ""
			(at 0 0 0)
			(layer "F.Fab")
			(effects
				(font
					(size 1.27 1.27)
				)
			)
		)
		(duplicate_pad_numbers_are_jumpers no)
		(fp_line
			(start -0.7874 -0.4064)
			(end 0.7874 -0.4064)
			(stroke
				(width 0.1524)
				(type default)
			)
			(layer "F.SilkS")
		)
		(fp_line
			(start -0.7874 0.4064)
			(end -0.7874 -0.4064)
			(stroke
				(width 0.1524)
				(type default)
			)
			(layer "F.SilkS")
		)
		(fp_line
			(start 0 0.381)
			(end 0 -0.381)
			(stroke
				(width 0.1524)
				(type default)
			)
			(layer "F.SilkS")
		)
		(fp_line
			(start 0.7874 -0.4064)
			(end 0.7874 0.4064)
			(stroke
				(width 0.1524)
				(type default)
			)
			(layer "F.SilkS")
		)
		(fp_line
			(start 0.7874 0.4064)
			(end -0.7874 0.4064)
			(stroke
				(width 0.1524)
				(type default)
			)
			(layer "F.SilkS")
		)
		(fp_poly
			(pts
				(xy -0.5334 0.254) (xy -0.635 0.254) (xy -0.635 0.2286) (xy -0.635 -0.254) (xy -0.5334 -0.254) (xy -0.5334 -0.2794)
				(xy 0.5334 -0.2794) (xy 0.5334 -0.254) (xy 0.635 -0.254) (xy 0.635 0.254) (xy 0.5334 0.254) (xy 0.5334 0.2794)
				(xy -0.508 0.2794) (xy -0.5334 0.2794)
			)
			(stroke
				(width 0)
				(type default)
			)
			(fill no)
			(layer "F.CrtYd")
		)
		(pad "1" smd rect
			(at 0.40005 0)
			(size 0.4572 0.508)
			(layers "F.Cu" "F.Mask" "F.Paste")
			(net "UART_T5_NODE4_RXD")
		)
		(pad "2" smd rect
			(at -0.40005 0)
			(size 0.4572 0.508)
			(layers "F.Cu" "F.Mask" "F.Paste")
			(net "GND")
		)
	)
)
